(kicad_pcb
	(version 20260206)
	(generator "pcbnew")
	(generator_version "10.0")
	(general
		(thickness 1.6)
		(legacy_teardrops no)
	)
	(paper "A4")
	(title_block
		(title "Bryce Canyon_F.DPB_16315-1-OCP.brd")
		(comment 1 "Bryce Canyon / footprints 113-120 of 2223")
	)
	(layers
		(0 "F.Cu" signal "TOP")
		(4 "In1.Cu" signal "L2GND")
		(6 "In2.Cu" signal "L3")
		(8 "In3.Cu" signal "L4GND")
		(10 "In4.Cu" signal "L5")
		(12 "In5.Cu" signal "L6VCC")
		(14 "In6.Cu" signal "L7VCC")
		(16 "In7.Cu" signal "L8")
		(18 "In8.Cu" signal "L9GND")
		(20 "In9.Cu" signal "L10")
		(22 "In10.Cu" signal "L11GND")
		(2 "B.Cu" signal "BOTTOM")
		(9 "F.Adhes" user "F.Adhesive")
		(11 "B.Adhes" user "B.Adhesive")
		(13 "F.Paste" user "Package Geometry/Pastemask Top")
		(15 "B.Paste" user "Package Geometry/Pastemask Bottom")
		(5 "F.SilkS" user "Ref Des/Silkscreen Top")
		(7 "B.SilkS" user "Ref Des/Silkscreen Bottom")
		(1 "F.Mask" user "Board Geometry/Soldermask Top")
		(3 "B.Mask" user "Board Geometry/Soldermask Bottom")
		(17 "Dwgs.User" user "User.Drawings")
		(19 "Cmts.User" user "User.Comments")
		(21 "Eco1.User" user "User.Eco1")
		(23 "Eco2.User" user "User.Eco2")
		(25 "Edge.Cuts" user "Board Geometry/Outline")
		(27 "Margin" user)
		(31 "F.CrtYd" user "Package Geometry/Place Bound Top")
		(29 "B.CrtYd" user "Package Geometry/Place Bound Bottom")
		(35 "F.Fab" user "Ref Des/Assembly Top")
		(33 "B.Fab" user "Ref Des/Assembly Bottom")
	)
	(footprint ""
		(layer "F.Cu")
		(at 264.693654 -223.251014)
		(property "Reference" "R601"
			(at 0 0 0)
			(layer "F.SilkS")
			(hide yes)
			(effects
				(font
					(size 1.27 1.27)
				)
			)
		)
		(property "Value" "2K2R2F-GP"
			(at 0.064008 -3.993896 0)
			(unlocked yes)
			(layer "F.Fab")
			(hide yes)
			(effects
				(font
					(size 1.016 1.016)
					(thickness 0.1524)
				)
			)
		)
		(property "Device Type" "R402H16"
			(at 0.064008 -5.517896 0)
			(unlocked yes)
			(layer "F.Fab")
			(hide yes)
			(effects
				(font
					(size 1.016 1.016)
					(thickness 0.1524)
				)
			)
		)
		(duplicate_pad_numbers_are_jumpers no)
		(fp_line
			(start -0.508 -0.9398)
			(end -0.508 0.9398)
			(stroke
				(width 0.1524)
				(type default)
			)
			(layer "F.SilkS")
		)
		(fp_line
			(start 0.508 -0.9398)
			(end -0.508 -0.9398)
			(stroke
				(width 0.1524)
				(type default)
			)
			(layer "F.SilkS")
		)
		(fp_rect
			(start -0.508 0.9398)
			(end 0.508 -0.9398)
			(stroke
				(width 0)
				(type default)
			)
			(fill no)
			(layer "F.CrtYd")
		)
		(fp_rect
			(start -0.508 0.9398)
			(end 0.508 -0.9398)
			(stroke
				(width 0)
				(type default)
			)
			(fill no)
			(layer "F.Fab")
		)
		(pad "1" smd custom
			(at 0 -0.4445)
			(size 0.1397 0.1397)
			(layers "F.Cu" "F.Mask" "F.Paste")
			(net "P3V3_STBY_A")
			(options
				(clearance outline)
				(anchor circle)
			)
			(primitives
				(gr_poly
					(pts
						(arc
							(start -0.1778 -0.2794)
							(mid -0.249642 -0.249642)
							(end -0.2794 -0.1778)
						)
						(arc
							(start -0.2794 0.1778)
							(mid -0.249642 0.249642)
							(end -0.1778 0.2794)
						)
						(arc
							(start 0.1778 0.2794)
							(mid 0.249642 0.249642)
							(end 0.2794 0.1778)
						)
						(arc
							(start 0.2794 -0.1778)
							(mid 0.249642 -0.249642)
							(end 0.1778 -0.2794)
						)
					)
					(width 0)
					(fill yes)
				)
			)
		)
		(pad "2" smd custom
			(at 0 0.4445)
			(size 0.1397 0.1397)
			(layers "F.Cu" "F.Mask" "F.Paste")
			(net "I2C_DPB_A_SDA")
			(options
				(clearance outline)
				(anchor circle)
			)
			(primitives
				(gr_poly
					(pts
						(arc
							(start -0.1778 -0.2794)
							(mid -0.249642 -0.249642)
							(end -0.2794 -0.1778)
						)
						(arc
							(start -0.2794 0.1778)
							(mid -0.249642 0.249642)
							(end -0.1778 0.2794)
						)
						(arc
							(start 0.1778 0.2794)
							(mid 0.249642 0.249642)
							(end 0.2794 0.1778)
						)
						(arc
							(start 0.2794 -0.1778)
							(mid 0.249642 -0.249642)
							(end 0.1778 -0.2794)
						)
					)
					(width 0)
					(fill yes)
				)
			)
		)
	)
	(footprint ""
		(layer "F.Cu")
		(at 237.987586 -346.78366 180)
		(property "Reference" "R165"
			(at 0 0 180)
			(layer "F.SilkS")
			(hide yes)
			(effects
				(font
					(size 1.27 1.27)
				)
			)
		)
		(property "Value" "16K2R2F-GP"
			(at 0.064008 -3.993896 180)
			(unlocked yes)
			(layer "F.Fab")
			(hide yes)
			(effects
				(font
					(size 1.016 1.016)
					(thickness 0.1524)
				)
			)
		)
		(property "Device Type" "R402H16"
			(at 0.064008 -5.517896 180)
			(unlocked yes)
			(layer "F.Fab")
			(hide yes)
			(effects
				(font
					(size 1.016 1.016)
					(thickness 0.1524)
				)
			)
		)
		(duplicate_pad_numbers_are_jumpers no)
		(fp_line
			(start 0.508 -0.9398)
			(end -0.508 -0.9398)
			(stroke
				(width 0.1524)
				(type default)
			)
			(layer "F.SilkS")
		)
		(fp_line
			(start -0.508 -0.9398)
			(end -0.508 0.9398)
			(stroke
				(width 0.1524)
				(type default)
			)
			(layer "F.SilkS")
		)
		(fp_rect
			(start -0.508 0.9398)
			(end 0.508 -0.9398)
			(stroke
				(width 0)
				(type default)
			)
			(fill no)
			(layer "F.CrtYd")
		)
		(fp_rect
			(start -0.508 0.9398)
			(end 0.508 -0.9398)
			(stroke
				(width 0)
				(type default)
			)
			(fill no)
			(layer "F.Fab")
		)
		(pad "1" smd custom
			(at 0 -0.4445 180)
			(size 0.1397 0.1397)
			(layers "F.Cu" "F.Mask" "F.Paste")
			(net "P5V_A_2")
			(options
				(clearance outline)
				(anchor circle)
			)
			(primitives
				(gr_poly
					(pts
						(arc
							(start -0.1778 -0.2794)
							(mid -0.249642 -0.249642)
							(end -0.2794 -0.1778)
						)
						(arc
							(start -0.2794 0.1778)
							(mid -0.249642 0.249642)
							(end -0.1778 0.2794)
						)
						(arc
							(start 0.1778 0.2794)
							(mid 0.249642 0.249642)
							(end 0.2794 0.1778)
						)
						(arc
							(start 0.2794 -0.1778)
							(mid 0.249642 -0.249642)
							(end 0.1778 -0.2794)
						)
					)
					(width 0)
					(fill yes)
				)
			)
		)
		(pad "2" smd custom
			(at 0 0.4445 180)
			(size 0.1397 0.1397)
			(layers "F.Cu" "F.Mask" "F.Paste")
			(net "P5V_A_2_SENSE")
			(options
				(clearance outline)
				(anchor circle)
			)
			(primitives
				(gr_poly
					(pts
						(arc
							(start -0.1778 -0.2794)
							(mid -0.249642 -0.249642)
							(end -0.2794 -0.1778)
						)
						(arc
							(start -0.2794 0.1778)
							(mid -0.249642 0.249642)
							(end -0.1778 0.2794)
						)
						(arc
							(start 0.1778 0.2794)
							(mid 0.249642 0.249642)
							(end 0.2794 0.1778)
						)
						(arc
							(start 0.2794 -0.1778)
							(mid 0.249642 -0.249642)
							(end 0.1778 -0.2794)
						)
					)
					(width 0)
					(fill yes)
				)
			)
		)
	)
	(footprint ""
		(layer "F.Cu")
		(at 277.9268 11.5824)
		(property "Reference" "R1296"
			(at 0 0 0)
			(layer "F.SilkS")
			(hide yes)
			(effects
				(font
					(size 1.27 1.27)
				)
			)
		)
		(property "Value" "3K3R3F-GP"
			(at -0.0254 -2.5146 0)
			(unlocked yes)
			(layer "F.Fab")
			(hide yes)
			(effects
				(font
					(size 1.016 1.016)
					(thickness 0.1524)
				)
			)
		)
		(property "Device Type" "R603H22"
			(at -0.0254 -4.0386 0)
			(unlocked yes)
			(layer "F.Fab")
			(hide yes)
			(effects
				(font
					(size 1.016 1.016)
					(thickness 0.1524)
				)
			)
		)
		(duplicate_pad_numbers_are_jumpers no)
		(fp_line
			(start -0.4826 0)
			(end -0.2032 0)
			(stroke
				(width 0.2032)
				(type default)
			)
			(layer "F.SilkS")
		)
		(fp_line
			(start 0.2032 0)
			(end 0.4826 0)
			(stroke
				(width 0.2032)
				(type default)
			)
			(layer "F.SilkS")
		)
		(fp_rect
			(start -0.5842 1.3335)
			(end 0.5842 -1.3335)
			(stroke
				(width 0)
				(type default)
			)
			(fill no)
			(layer "F.CrtYd")
		)
		(fp_rect
			(start -0.5842 1.3335)
			(end 0.5842 -1.3335)
			(stroke
				(width 0)
				(type default)
			)
			(fill no)
			(layer "F.Fab")
		)
		(pad "1" smd custom
			(at 0 -0.762)
			(size 0.2159 0.2159)
			(layers "F.Cu" "F.Mask" "F.Paste")
			(net "P12V_IN")
			(options
				(clearance outline)
				(anchor circle)
			)
			(primitives
				(gr_poly
					(pts
						(arc
							(start -0.3302 -0.4318)
							(mid -0.402042 -0.402042)
							(end -0.4318 -0.3302)
						)
						(arc
							(start -0.4318 0.3302)
							(mid -0.402042 0.402042)
							(end -0.3302 0.4318)
						)
						(arc
							(start 0.3302 0.4318)
							(mid 0.402042 0.402042)
							(end 0.4318 0.3302)
						)
						(arc
							(start 0.4318 -0.3302)
							(mid 0.402042 -0.402042)
							(end 0.3302 -0.4318)
						)
					)
					(width 0)
					(fill yes)
				)
			)
		)
		(pad "2" smd custom
			(at 0 0.762)
			(size 0.2159 0.2159)
			(layers "F.Cu" "F.Mask" "F.Paste")
			(net "VCCP")
			(options
				(clearance outline)
				(anchor circle)
			)
			(primitives
				(gr_poly
					(pts
						(arc
							(start -0.3302 -0.4318)
							(mid -0.402042 -0.402042)
							(end -0.4318 -0.3302)
						)
						(arc
							(start -0.4318 0.3302)
							(mid -0.402042 0.402042)
							(end -0.3302 0.4318)
						)
						(arc
							(start 0.3302 0.4318)
							(mid 0.402042 0.402042)
							(end 0.4318 0.3302)
						)
						(arc
							(start 0.4318 -0.3302)
							(mid 0.402042 -0.402042)
							(end 0.3302 -0.4318)
						)
					)
					(width 0)
					(fill yes)
				)
			)
		)
	)
	(footprint ""
		(layer "F.Cu")
		(at 259.20192 -230.251)
		(property "Reference" "R93"
			(at 0 0 0)
			(layer "F.SilkS")
			(hide yes)
			(effects
				(font
					(size 1.27 1.27)
				)
			)
		)
		(property "Value" "0R2J-2-GP"
			(at 0.064008 -3.993896 0)
			(unlocked yes)
			(layer "F.Fab")
			(hide yes)
			(effects
				(font
					(size 1.016 1.016)
					(thickness 0.1524)
				)
			)
		)
		(property "Device Type" "R402H16"
			(at 0.064008 -5.517896 0)
			(unlocked yes)
			(layer "F.Fab")
			(hide yes)
			(effects
				(font
					(size 1.016 1.016)
					(thickness 0.1524)
				)
			)
		)
		(duplicate_pad_numbers_are_jumpers no)
		(fp_line
			(start -0.508 -0.9398)
			(end -0.508 0.9398)
			(stroke
				(width 0.1524)
				(type default)
			)
			(layer "F.SilkS")
		)
		(fp_line
			(start 0.508 -0.9398)
			(end -0.508 -0.9398)
			(stroke
				(width 0.1524)
				(type default)
			)
			(layer "F.SilkS")
		)
		(fp_rect
			(start -0.508 0.9398)
			(end 0.508 -0.9398)
			(stroke
				(width 0)
				(type default)
			)
			(fill no)
			(layer "F.CrtYd")
		)
		(fp_rect
			(start -0.508 0.9398)
			(end 0.508 -0.9398)
			(stroke
				(width 0)
				(type default)
			)
			(fill no)
			(layer "F.Fab")
		)
		(pad "1" smd custom
			(at 0 -0.4445)
			(size 0.1397 0.1397)
			(layers "F.Cu" "F.Mask" "F.Paste")
			(net "IO_EXP3_SCL")
			(options
				(clearance outline)
				(anchor circle)
			)
			(primitives
				(gr_poly
					(pts
						(arc
							(start -0.1778 -0.2794)
							(mid -0.249642 -0.249642)
							(end -0.2794 -0.1778)
						)
						(arc
							(start -0.2794 0.1778)
							(mid -0.249642 0.249642)
							(end -0.1778 0.2794)
						)
						(arc
							(start 0.1778 0.2794)
							(mid 0.249642 0.249642)
							(end 0.2794 0.1778)
						)
						(arc
							(start 0.2794 -0.1778)
							(mid 0.249642 -0.249642)
							(end 0.1778 -0.2794)
						)
					)
					(width 0)
					(fill yes)
				)
			)
		)
		(pad "2" smd custom
			(at 0 0.4445)
			(size 0.1397 0.1397)
			(layers "F.Cu" "F.Mask" "F.Paste")
			(net "I2C_DRIVE_A_PWR_SCL")
			(options
				(clearance outline)
				(anchor circle)
			)
			(primitives
				(gr_poly
					(pts
						(arc
							(start -0.1778 -0.2794)
							(mid -0.249642 -0.249642)
							(end -0.2794 -0.1778)
						)
						(arc
							(start -0.2794 0.1778)
							(mid -0.249642 0.249642)
							(end -0.1778 0.2794)
						)
						(arc
							(start 0.1778 0.2794)
							(mid 0.249642 0.249642)
							(end 0.2794 0.1778)
						)
						(arc
							(start 0.2794 -0.1778)
							(mid 0.249642 -0.249642)
							(end 0.1778 -0.2794)
						)
					)
					(width 0)
					(fill yes)
				)
			)
		)
	)
	(footprint ""
		(layer "F.Cu")
		(at 365.0488 -133.6294 -90)
		(property "Reference" "R1090"
			(at 0 0 270)
			(layer "F.SilkS")
			(hide yes)
			(effects
				(font
					(size 1.27 1.27)
				)
			)
		)
		(property "Value" "100KR2F-L1-GP"
			(at 0.064008 -3.993896 270)
			(unlocked yes)
			(layer "F.Fab")
			(hide yes)
			(effects
				(font
					(size 1.016 1.016)
					(thickness 0.1524)
				)
			)
		)
		(property "Device Type" "R402H16"
			(at 0.064008 -5.517896 270)
			(unlocked yes)
			(layer "F.Fab")
			(hide yes)
			(effects
				(font
					(size 1.016 1.016)
					(thickness 0.1524)
				)
			)
		)
		(duplicate_pad_numbers_are_jumpers no)
		(fp_line
			(start -0.508 -0.9398)
			(end -0.508 0.9398)
			(stroke
				(width 0.1524)
				(type default)
			)
			(layer "F.SilkS")
		)
		(fp_line
			(start 0.508 -0.9398)
			(end -0.508 -0.9398)
			(stroke
				(width 0.1524)
				(type default)
			)
			(layer "F.SilkS")
		)
		(fp_rect
			(start -0.508 0.9398)
			(end 0.508 -0.9398)
			(stroke
				(width 0)
				(type default)
			)
			(fill no)
			(layer "F.CrtYd")
		)
		(fp_rect
			(start -0.508 0.9398)
			(end 0.508 -0.9398)
			(stroke
				(width 0)
				(type default)
			)
			(fill no)
			(layer "F.Fab")
		)
		(pad "1" smd custom
			(at 0 -0.4445 270)
			(size 0.1397 0.1397)
			(layers "F.Cu" "F.Mask" "F.Paste")
			(net "MB1_VCAP_R")
			(options
				(clearance outline)
				(anchor circle)
			)
			(primitives
				(gr_poly
					(pts
						(arc
							(start -0.1778 -0.2794)
							(mid -0.249642 -0.249642)
							(end -0.2794 -0.1778)
						)
						(arc
							(start -0.2794 0.1778)
							(mid -0.249642 0.249642)
							(end -0.1778 0.2794)
						)
						(arc
							(start 0.1778 0.2794)
							(mid 0.249642 0.249642)
							(end 0.2794 0.1778)
						)
						(arc
							(start 0.2794 -0.1778)
							(mid 0.249642 -0.249642)
							(end 0.1778 -0.2794)
						)
					)
					(width 0)
					(fill yes)
				)
			)
		)
		(pad "2" smd custom
			(at 0 0.4445 270)
			(size 0.1397 0.1397)
			(layers "F.Cu" "F.Mask" "F.Paste")
			(net "MB1_PSET_R")
			(options
				(clearance outline)
				(anchor circle)
			)
			(primitives
				(gr_poly
					(pts
						(arc
							(start -0.1778 -0.2794)
							(mid -0.249642 -0.249642)
							(end -0.2794 -0.1778)
						)
						(arc
							(start -0.2794 0.1778)
							(mid -0.249642 0.249642)
							(end -0.1778 0.2794)
						)
						(arc
							(start 0.1778 0.2794)
							(mid 0.249642 0.249642)
							(end 0.2794 0.1778)
						)
						(arc
							(start 0.2794 -0.1778)
							(mid 0.249642 -0.249642)
							(end 0.1778 -0.2794)
						)
					)
					(width 0)
					(fill yes)
				)
			)
		)
	)
	(footprint ""
		(layer "F.Cu")
		(at 303.090072 -14.774672 90)
		(property "Reference" "C523"
			(at 0 0 90)
			(layer "F.SilkS")
			(hide yes)
			(effects
				(font
					(size 1.27 1.27)
				)
			)
		)
		(property "Value" "SC2D2U25V5KX-2-GP"
			(at -0.0762 -6.1214 90)
			(unlocked yes)
			(layer "F.Fab")
			(hide yes)
			(effects
				(font
					(size 1.016 1.016)
					(thickness 0.1524)
				)
			)
		)
		(property "Device Type" "C805H54"
			(at -0.0762 -8.1534 90)
			(unlocked yes)
			(layer "F.Fab")
			(hide yes)
			(effects
				(font
					(size 1.016 1.016)
					(thickness 0.1524)
				)
			)
		)
		(duplicate_pad_numbers_are_jumpers no)
		(fp_line
			(start 0.635 0)
			(end -0.635 0)
			(stroke
				(width 0.508)
				(type default)
			)
			(layer "F.SilkS")
		)
		(fp_rect
			(start -0.9652 1.778)
			(end 0.9652 -1.778)
			(stroke
				(width 0)
				(type default)
			)
			(fill no)
			(layer "F.CrtYd")
		)
		(fp_poly
			(pts
				(xy -0.9652 -1.778) (xy 0.9652 -1.778) (xy 0.9652 1.778) (xy -0.9652 1.778)
			)
			(stroke
				(width 0)
				(type default)
			)
			(fill no)
			(layer "F.Fab")
		)
		(pad "1" smd rect
			(at 0 -0.9652 90)
			(size 1.397 1.143)
			(layers "F.Cu" "F.Mask" "F.Paste")
			(net "P12V_B_COMP")
		)
		(pad "2" smd rect
			(at 0 0.9652 90)
			(size 1.397 1.143)
			(layers "F.Cu" "F.Mask" "F.Paste")
			(net "GND")
		)
	)
	(footprint ""
		(layer "F.Cu")
		(at 479.340926 -189.462918 180)
		(property "Reference" "C346"
			(at 0 0 180)
			(layer "F.SilkS")
			(hide yes)
			(effects
				(font
					(size 1.27 1.27)
				)
			)
		)
		(property "Value" "SC1U25V3KX-GP"
			(at 0 -2.8194 180)
			(unlocked yes)
			(layer "F.Fab")
			(hide yes)
			(effects
				(font
					(size 1.016 1.016)
					(thickness 0.1524)
				)
			)
		)
		(property "Device Type" "C603H36"
			(at 0 -4.3434 180)
			(unlocked yes)
			(layer "F.Fab")
			(hide yes)
			(effects
				(font
					(size 1.016 1.016)
					(thickness 0.1524)
				)
			)
		)
		(duplicate_pad_numbers_are_jumpers no)
		(fp_line
			(start 0.508 0)
			(end -0.508 0)
			(stroke
				(width 0.2032)
				(type default)
			)
			(layer "F.SilkS")
		)
		(fp_rect
			(start -0.5842 1.3335)
			(end 0.5842 -1.3335)
			(stroke
				(width 0)
				(type default)
			)
			(fill no)
			(layer "F.CrtYd")
		)
		(fp_rect
			(start -0.5842 1.3335)
			(end 0.5842 -1.3335)
			(stroke
				(width 0)
				(type default)
			)
			(fill no)
			(layer "F.Fab")
		)
		(pad "1" smd custom
			(at 0 -0.762 180)
			(size 0.2159 0.2159)
			(layers "F.Cu" "F.Mask" "F.Paste")
			(net "P12V_HDD23")
			(options
				(clearance outline)
				(anchor circle)
			)
			(primitives
				(gr_poly
					(pts
						(arc
							(start -0.3302 -0.4318)
							(mid -0.402042 -0.402042)
							(end -0.4318 -0.3302)
						)
						(arc
							(start -0.4318 0.3302)
							(mid -0.402042 0.402042)
							(end -0.3302 0.4318)
						)
						(arc
							(start 0.3302 0.4318)
							(mid 0.402042 0.402042)
							(end 0.4318 0.3302)
						)
						(arc
							(start 0.4318 -0.3302)
							(mid 0.402042 -0.402042)
							(end 0.3302 -0.4318)
						)
					)
					(width 0)
					(fill yes)
				)
			)
		)
		(pad "2" smd custom
			(at 0 0.762 180)
			(size 0.2159 0.2159)
			(layers "F.Cu" "F.Mask" "F.Paste")
			(net "GND")
			(options
				(clearance outline)
				(anchor circle)
			)
			(primitives
				(gr_poly
					(pts
						(arc
							(start -0.3302 -0.4318)
							(mid -0.402042 -0.402042)
							(end -0.4318 -0.3302)
						)
						(arc
							(start -0.4318 0.3302)
							(mid -0.402042 0.402042)
							(end -0.3302 0.4318)
						)
						(arc
							(start 0.3302 0.4318)
							(mid 0.402042 0.402042)
							(end 0.4318 0.3302)
						)
						(arc
							(start 0.4318 -0.3302)
							(mid 0.402042 -0.402042)
							(end 0.3302 -0.4318)
						)
					)
					(width 0)
					(fill yes)
				)
			)
		)
	)
	(footprint ""
		(layer "F.Cu")
		(at 3.849878 -5.499862)
		(property "Reference" ""
			(at 0 0 0)
			(layer "F.SilkS")
			(hide yes)
			(effects
				(font
					(size 1.27 1.27)
				)
			)
		)
		(property "Value" "*"
			(at -4.729734 -0.095504 0)
			(unlocked yes)
			(layer "F.Fab")
			(hide yes)
			(effects
				(font
					(size 1.016 1.016)
					(thickness 0.1524)
				)
			)
		)
		(duplicate_pad_numbers_are_jumpers no)
		(fp_poly
			(pts
				(arc
					(start 4.064 0)
					(mid -4.064 0)
					(end 4.064 0)
				)
			)
			(stroke
				(width 0)
				(type default)
			)
			(fill no)
			(layer "B.CrtYd")
		)
		(fp_poly
			(pts
				(arc
					(start 4.064 0)
					(mid -4.064 0)
					(end 4.064 0)
				)
			)
			(stroke
				(width 0)
				(type default)
			)
			(fill no)
			(layer "F.CrtYd")
		)
		(fp_poly
			(pts
				(arc
					(start 4.064 0)
					(mid -4.064 0)
					(end 4.064 0)
				)
			)
			(stroke
				(width 0)
				(type default)
			)
			(fill no)
			(layer "B.Fab")
		)
		(fp_poly
			(pts
				(arc
					(start 4.064 0)
					(mid -4.064 0)
					(end 4.064 0)
				)
			)
			(stroke
				(width 0)
				(type default)
			)
			(fill no)
			(layer "F.Fab")
		)
		(pad "1" thru_hole circle
			(at 0 0)
			(size 7.5184 7.5184)
			(drill 4.2164)
			(layers "*.Cu" "*.Mask")
			(remove_unused_layers no)
			(net "Net_25")
			(clearance -1.143)
			(thermal_gap 0.3048)
			(padstack
				(mode front_inner_back)
				(layer "Inner"
					(shape circle)
					(size 4.6228 4.6228)
					(clearance 0.3048)
				)
				(layer "B.Cu"
					(shape circle)
					(size 7.5184 7.5184)
					(clearance -1.143)
				)
			)
		)
	)
)
